# SCM (Grand Teton) — schematic netlist excerpt (pin names and nets, part order shuffled) for the footprints in the layout excerpt that follows; sources: Cadence DE-HDL packaged netlist, KiCad conversion of 12092022_DA0F0TMDCD0_F0T_Management_Board_D_brd_V3_OCP.brd

PC205  Q_CAP  0.1UF 25V 10% X7R  pkg 0402  page 51 : A = EN_P5V_AUX ; B = GND
PC272  Q_CAP  68PF 50V 5% COG  pkg C0402  page 51 : A = P5V_AUX_FB ; B = P5V_AUX

(kicad_pcb
	(version 20260206)
	(generator "pcbnew")
	(generator_version "10.0")
	(general
		(thickness 1.6)
		(legacy_teardrops no)
	)
	(paper "A4")
	(title_block
		(title "12092022_DA0F0TMDCD0_F0T_Management_Board_D_brd_V3_OCP.brd")
		(comment 1 "Grand Teton / footprints 596-597 of 1440")
	)
	(layers
		(0 "F.Cu" signal "TOP")
		(4 "In1.Cu" signal "GND")
		(6 "In2.Cu" signal "IN1")
		(8 "In3.Cu" signal "GND1")
		(10 "In4.Cu" signal "IN2")
		(12 "In5.Cu" signal "VCC")
		(14 "In6.Cu" signal "VCC1")
		(16 "In7.Cu" signal "IN3")
		(18 "In8.Cu" signal "GND2")
		(20 "In9.Cu" signal "IN4")
		(22 "In10.Cu" signal "GND3")
		(2 "B.Cu" signal "BOTTOM")
		(9 "F.Adhes" user "F.Adhesive")
		(11 "B.Adhes" user "B.Adhesive")
		(13 "F.Paste" user "Package Geometry/Pastemask Top")
		(15 "B.Paste" user "Package Geometry/Pastemask Bottom")
		(5 "F.SilkS" user "Ref Des/Silkscreen Top")
		(7 "B.SilkS" user "Ref Des/Silkscreen Bottom")
		(1 "F.Mask" user "Board Geometry/Soldermask Top")
		(3 "B.Mask" user "Board Geometry/Soldermask Bottom")
		(17 "Dwgs.User" user "User.Drawings")
		(19 "Cmts.User" user "User.Comments")
		(21 "Eco1.User" user "User.Eco1")
		(23 "Eco2.User" user "User.Eco2")
		(25 "Edge.Cuts" user "Board Geometry/Outline")
		(27 "Margin" user)
		(31 "F.CrtYd" user "Package Geometry/Place Bound Top")
		(29 "B.CrtYd" user "Package Geometry/Place Bound Bottom")
		(35 "F.Fab" user "Ref Des/Assembly Top")
		(33 "B.Fab" user "Ref Des/Assembly Bottom")
	)
	(footprint ""
		(layer "F.Cu")
		(at 11.761978 -52.008532 90)
		(property "Reference" "PC205"
			(at 0 0 90)
			(layer "F.SilkS")
			(hide yes)
			(effects
				(font
					(size 1.27 1.27)
				)
			)
		)
		(property "Value" ""
			(at 0 0 90)
			(layer "F.Fab")
			(effects
				(font
					(size 1.27 1.27)
				)
			)
		)
		(duplicate_pad_numbers_are_jumpers no)
		(fp_line
			(start 0.7874 -0.4064)
			(end 0.7874 0.4064)
			(stroke
				(width 0.1524)
				(type default)
			)
			(layer "F.SilkS")
		)
		(fp_line
			(start -0.7874 -0.4064)
			(end 0.7874 -0.4064)
			(stroke
				(width 0.1524)
				(type default)
			)
			(layer "F.SilkS")
		)
		(fp_line
			(start 0.7874 0.4064)
			(end -0.7874 0.4064)
			(stroke
				(width 0.1524)
				(type default)
			)
			(layer "F.SilkS")
		)
		(fp_line
			(start -0.7874 0.4064)
			(end -0.7874 -0.4064)
			(stroke
				(width 0.1524)
				(type default)
			)
			(layer "F.SilkS")
		)
		(fp_line
			(start -0.12065 -0.305054)
			(end -0.12065 -0.2794)
			(stroke
				(width 0.1)
				(type default)
			)
			(layer "F.Fab")
		)
		(fp_line
			(start -0.67945 -0.305054)
			(end -0.12065 -0.305054)
			(stroke
				(width 0.1)
				(type default)
			)
			(layer "F.Fab")
		)
		(fp_line
			(start 0.67945 -0.3048)
			(end 0.67945 0.3048)
			(stroke
				(width 0.1)
				(type default)
			)
			(layer "F.Fab")
		)
		(fp_line
			(start 0.12065 -0.3048)
			(end 0.67945 -0.3048)
			(stroke
				(width 0.1)
				(type default)
			)
			(layer "F.Fab")
		)
		(fp_line
			(start 0.12065 -0.2794)
			(end 0.12065 -0.3048)
			(stroke
				(width 0.1)
				(type default)
			)
			(layer "F.Fab")
		)
		(fp_line
			(start -0.12065 -0.2794)
			(end 0.12065 -0.2794)
			(stroke
				(width 0.1)
				(type default)
			)
			(layer "F.Fab")
		)
		(fp_line
			(start 0.120396 0.2794)
			(end -0.12065 0.2794)
			(stroke
				(width 0.1)
				(type default)
			)
			(layer "F.Fab")
		)
		(fp_line
			(start -0.12065 0.2794)
			(end -0.12065 0.3048)
			(stroke
				(width 0.1)
				(type default)
			)
			(layer "F.Fab")
		)
		(fp_line
			(start 0.67945 0.3048)
			(end 0.120396 0.3048)
			(stroke
				(width 0.1)
				(type default)
			)
			(layer "F.Fab")
		)
		(fp_line
			(start 0.120396 0.3048)
			(end 0.120396 0.2794)
			(stroke
				(width 0.1)
				(type default)
			)
			(layer "F.Fab")
		)
		(fp_line
			(start -0.12065 0.3048)
			(end -0.67945 0.3048)
			(stroke
				(width 0.1)
				(type default)
			)
			(layer "F.Fab")
		)
		(fp_line
			(start -0.67945 0.3048)
			(end -0.67945 -0.305054)
			(stroke
				(width 0.1)
				(type default)
			)
			(layer "F.Fab")
		)
		(pad "1" smd circle
			(at -0.40005 0 90)
			(size 0 0)
			(layers "F.Cu" "F.Mask" "F.Paste")
			(net "EN_P5V_AUX")
		)
		(pad "2" smd circle
			(at 0.40005 0 90)
			(size 0 0)
			(layers "F.Cu" "F.Mask" "F.Paste")
			(net "GND")
		)
	)
	(footprint ""
		(layer "F.Cu")
		(at 12.799568 -50.110898 -90)
		(property "Reference" "PC272"
			(at 0 0 270)
			(layer "F.SilkS")
			(hide yes)
			(effects
				(font
					(size 1.27 1.27)
				)
			)
		)
		(property "Value" ""
			(at 0 0 270)
			(layer "F.Fab")
			(effects
				(font
					(size 1.27 1.27)
				)
			)
		)
		(duplicate_pad_numbers_are_jumpers no)
		(fp_line
			(start -0.7874 0.4064)
			(end -0.7874 -0.4064)
			(stroke
				(width 0.1524)
				(type default)
			)
			(layer "F.SilkS")
		)
		(fp_line
			(start 0.7874 0.4064)
			(end -0.7874 0.4064)
			(stroke
				(width 0.1524)
				(type default)
			)
			(layer "F.SilkS")
		)
		(fp_line
			(start -0.7874 -0.4064)
			(end 0.7874 -0.4064)
			(stroke
				(width 0.1524)
				(type default)
			)
			(layer "F.SilkS")
		)
		(fp_line
			(start 0.7874 -0.4064)
			(end 0.7874 0.4064)
			(stroke
				(width 0.1524)
				(type default)
			)
			(layer "F.SilkS")
		)
		(fp_line
			(start -0.67945 0.3048)
			(end -0.67945 -0.305054)
			(stroke
				(width 0.1)
				(type default)
			)
			(layer "F.Fab")
		)
		(fp_line
			(start -0.12065 0.3048)
			(end -0.67945 0.3048)
			(stroke
				(width 0.1)
				(type default)
			)
			(layer "F.Fab")
		)
		(fp_line
			(start 0.120396 0.3048)
			(end 0.120396 0.2794)
			(stroke
				(width 0.1)
				(type default)
			)
			(layer "F.Fab")
		)
		(fp_line
			(start 0.67945 0.3048)
			(end 0.120396 0.3048)
			(stroke
				(width 0.1)
				(type default)
			)
			(layer "F.Fab")
		)
		(fp_line
			(start -0.12065 0.2794)
			(end -0.12065 0.3048)
			(stroke
				(width 0.1)
				(type default)
			)
			(layer "F.Fab")
		)
		(fp_line
			(start 0.120396 0.2794)
			(end -0.12065 0.2794)
			(stroke
				(width 0.1)
				(type default)
			)
			(layer "F.Fab")
		)
		(fp_line
			(start -0.12065 -0.2794)
			(end 0.12065 -0.2794)
			(stroke
				(width 0.1)
				(type default)
			)
			(layer "F.Fab")
		)
		(fp_line
			(start 0.12065 -0.2794)
			(end 0.12065 -0.3048)
			(stroke
				(width 0.1)
				(type default)
			)
			(layer "F.Fab")
		)
		(fp_line
			(start 0.12065 -0.3048)
			(end 0.67945 -0.3048)
			(stroke
				(width 0.1)
				(type default)
			)
			(layer "F.Fab")
		)
		(fp_line
			(start 0.67945 -0.3048)
			(end 0.67945 0.3048)
			(stroke
				(width 0.1)
				(type default)
			)
			(layer "F.Fab")
		)
		(fp_line
			(start -0.67945 -0.305054)
			(end -0.12065 -0.305054)
			(stroke
				(width 0.1)
				(type default)
			)
			(layer "F.Fab")
		)
		(fp_line
			(start -0.12065 -0.305054)
			(end -0.12065 -0.2794)
			(stroke
				(width 0.1)
				(type default)
			)
			(layer "F.Fab")
		)
		(pad "1" smd circle
			(at -0.40005 0 270)
			(size 0 0)
			(layers "F.Cu" "F.Mask" "F.Paste")
			(net "P5V_AUX_FB")
		)
		(pad "2" smd circle
			(at 0.40005 0 270)
			(size 0 0)
			(layers "F.Cu" "F.Mask" "F.Paste")
			(net "P5V_AUX")
		)
	)
)
